FILE_TYPE = CONNECTIVITY;
{Allegro Design Entry HDL 16.6-p007 (v16-6-112F) 10/10/2012}
"PAGE_NUMBER" = 170;
0"NC";
1"P3V3_STBY\g";
2"GND\g";
3"P3V3_STBY\g";
4"GND\g";
5"P3V3_STBY\g";
6"P3V3_STBY\g";
7"GND\g";
8"GND\g";
9"P3V3_STBY\g";
10"GND\g";
11"P3V3_STBY\g";
12"P3V3_STBY\g";
13"P3V3_STBY\g";
14"GND\g";
15"P3V3_STBY\g";
16"GND\g";
17"P3V3_STBY\g";
18"GND\g";
19"GND\g";
20"P3V3_STBY\g";
21"P3V3_STBY\g";
22"FM_FAST_PROCHOT_THROTTLE_IN_N";
23"FM_FAST_PROCHOT_AND_OUT_0_N";
24"IRQ_FORCE_NM_THROTTLE_N";
25"FM_OC_DETECT_N";
26"IRQ_FORCE_NM_THROTTLE_R_N";
27"IRQ_SML1_PMBUS_ALERT_BUF_N";
28"FM_PMBUS_ALERT_BUF_EN";
29"IRQ_SML1_PMBUS_ALERT_N";
30"FM_FAST_PROCHOT_AND_OUT_1_N";
31"FM_THROTTLE_N";
32"FM_THROTTLE_R1_N";
33"FM_FAST_PROCHOT_THROTTLE_DLY_BUF_N";
34"FM_HSC_TIMER_EXP_N";
35"IRQ_UV_DETECT_N";
36"FM_FAST_PROCHOT_EN";
37"FM_FAST_PROCHOT_THROTTLE_DLY_N";
38"FM_FAST_PROCHOT_EN_N";
39"FM_PMBUS_ALERT_BUF_EN_N";
%"TTL08"
"1","(-1400,4375)","0","mstr_ttl","I10";
;
CDS_SEC"4"
SEC_TYPE"QFN15"
BOM_COST"FAST_PROCHOT"
SEC"4"
ROOM"FAST_PROCHOT"
PACK_TYPE"QFN15"
CDS_LOCATION"U8E1"
CDS_LIB"mstr_ttl"
POWER_GROUP"VCC=P3V3_STBY;GND=GND;TH=GND"
LOCATION"U8E1"
VALUE"74LVC08A"
PART_NUMBER"D90404-001"
MATERIAL"IC";
"A <SIZE-1..0>"
$PN"1"24;
"B <SIZE-1..0>"
$PN"2"25;
"Y <SIZE-1..0>"
$PN"3"23;
%"TTL08"
"1","(-1400,3650)","0","mstr_ttl","I11";
;
CDS_SEC"3"
SEC_TYPE"QFN15"
BOM_COST"FAST_PROCHOT"
SEC"3"
CDS_LOCATION"U8E1"
ROOM"FAST_PROCHOT"
PACK_TYPE"QFN15"
CDS_LIB"mstr_ttl"
POWER_GROUP"VCC=P3V3_STBY;GND=GND;TH=GND"
VALUE"74LVC08A"
LOCATION"U8E1"
MATERIAL"IC"
PART_NUMBER"D90404-001";
"A <SIZE-1..0>"
$PN"4"35;
"B <SIZE-1..0>"
$PN"5"34;
"Y <SIZE-1..0>"
$PN"6"30;
%"TTL08"
"1","(-250,4075)","0","mstr_ttl","I12";
;
CDS_SEC"1"
BOM_COST"FAST_PROCHOT"
SEC"1"
SEC_TYPE"QFN15"
PACK_TYPE"QFN15"
ROOM"FAST_PROCHOT"
CDS_LOCATION"U8E1"
CDS_LIB"mstr_ttl"
POWER_GROUP"VCC=P3V3_STBY;GND=GND;TH=GND"
VALUE"74LVC08A"
LOCATION"U8E1"
MATERIAL"IC"
PART_NUMBER"D90404-001";
"A <SIZE-1..0>"
$PN"12"23;
"B <SIZE-1..0>"
$PN"13"30;
"Y <SIZE-1..0>"
$PN"11"22;
%"RES"
"2","(-2350,5250)","0","mstr_discrete","I2";
;
CDS_SEC"1"
SEC_TYPE"0402"
BOM_COST"FAST_PROCHOT"
SEC"1"
ROOM"FAST_PROCHOT"
CDS_LOCATION"R2P3"
CDS_LIB"mstr_discrete"
PART_NUMBER"G21796-072"
WATTAGE"1/16W"
MATERIAL"CHIP"
TOLERANCE"1%"
VALUE"4.75K"
LOCATION"R2P3"
PACK_TYPE"0402";
"A"
$PN"1"1;
"B"
$PN"2"26;
%"TTL1G126_A"
"1","(-2525,2525)","0","mstr_ttl","I20";
;
CDS_SEC"1"
CDS_LIB"mstr_ttl"
SEC_TYPE"SOT"
BOM_COST"FAST_PROCHOT"
SEC"1"
CDS_LOCATION"U1R2"
ROOM"FAST_PROCHOT"
PACK_TYPE"SOT"
POWER_GROUP"VCC=P3V3_STBY;GND=GND;"
PART_NUMBER"A79322-001"
MATERIAL"IC"
VALUE"74HC1G126"
LOCATION"U1R2";
"OE"
$PN"1"36;
"Y"
$PN"4"33;
"A"
$PN"2"37;
%"P3V3_STBY"
"1","(-2350,5475)","0","mstr_symbols","I3";
;
VOLTAGE"3.3V"
SIZE"1B"
CDS_LIB"mstr_symbols"
BODY_TYPE"PLUMBING"
HDL_POWER"P3V3_STBY";
"G\NAC"1;
%"CAP_A"
"1","(-5150,1325)","0","dev_discrete","I30";
;
BOM_COST"FAST_PROCHOT"
SEC"1"
SEC_TYPE"0402V"
CDS_LOCATION"C1R27"
ROOM"FAST_PROCHOT"
CDS_SEC"1"
CDS_LIB"dev_discrete"
MATERIAL"X7R"
VOLTAGE"16V"
PACK_TYPE"0402V"
TOLERANCE"10%"
VALUE"0.1UF"
PART_NUMBER"A36096-030"
LOCATION"C1R27";
"B"
$PN"2"2;
"A"
$PN"1"3;
%"GND"
"1","(-5150,1050)","0","mstr_symbols","I31";
;
SIZE"1B"
CDS_LIB"mstr_symbols"
HDL_POWER"GND"
BODY_TYPE"PLUMBING"
VOLTAGE"0.0V";
"A\NAC"2;
%"P3V3_STBY"
"1","(-5150,1575)","0","mstr_symbols","I32";
;
SIZE"1B"
CDS_LIB"mstr_symbols"
BODY_TYPE"PLUMBING"
VOLTAGE"3.3V"
HDL_POWER"P3V3_STBY";
"G\NAC"3;
%"CAP_A"
"1","(-425,4775)","0","dev_discrete","I33";
;
CDS_LOCATION"C8D2"
ROOM"FAST_PROCHOT"
CDS_SEC"1"
SEC_TYPE"0402V"
BOM_COST"FAST_PROCHOT"
SEC"1"
CDS_LIB"dev_discrete"
VALUE"0.1UF"
PART_NUMBER"A36096-030"
LOCATION"C8D2"
MATERIAL"X7R"
VOLTAGE"16V"
TOLERANCE"10%"
PACK_TYPE"0402V";
"B"
$PN"2"4;
"A"
$PN"1"5;
%"GND"
"1","(-425,4500)","0","mstr_symbols","I34";
;
HDL_POWER"GND"
BODY_TYPE"PLUMBING"
SIZE"1B"
CDS_LIB"mstr_symbols"
VOLTAGE"0.0V";
"A\NAC"4;
%"P3V3_STBY"
"1","(-425,5025)","0","mstr_symbols","I35";
;
SIZE"1B"
VOLTAGE"3.3V"
BODY_TYPE"PLUMBING"
CDS_LIB"mstr_symbols"
HDL_POWER"P3V3_STBY";
"G\NAC"5;
%"TTL1G126_A"
"1","(-3500,4775)","0","mstr_ttl","I38";
;
CDS_SEC"1"
CDS_LOCATION"U8D5"
SEC"1"
SEC_TYPE"SOT"
BOM_COST"PROC_SIDEBAND"
ROOM"PROC_SIDEBAND"
PACK_TYPE"SOT"
CDS_LIB"mstr_ttl"
POWER_GROUP"VCC=P3V3_STBY;GND=GND;"
VALUE"74HC1G126"
PART_NUMBER"A79322-001"
LOCATION"U8D5"
MATERIAL"IC";
"OE"
$PN"1"28;
"Y"
$PN"4"27;
"A"
$PN"2"29;
%"P3V3_STBY"
"1","(-1575,5350)","0","mstr_symbols","I39";
;
SIZE"1B"
CDS_LIB"mstr_symbols"
BODY_TYPE"PLUMBING"
HDL_POWER"P3V3_STBY"
VOLTAGE"3.3V";
"G\NAC"6;
%"TTL1G07_A"
"1","(-2625,4775)","0","mstr_ttl","I4";
;
BOM_COST"FAST_PROCHOT"
CDS_LIB"mstr_ttl"
CDS_SEC"1"
$SEC"1"
CDS_LOCATION"U8D3"
ROOM"FAST_PROCHOT"
PACK_TYPE"SOP"
VALUE"74LVC1G07"
PART_NUMBER"C88419-001"
LOCATION"U8D3"
POWER_GROUP"VCC=P3V3_STBY;GND=GND"
MATERIAL"IC";
"Y"
$PN"4"26;
"A"
$PN"2"27;
%"CAP_A"
"1","(-1575,5100)","0","dev_discrete","I40";
;
CDS_SEC"1"
SEC_TYPE"0402V"
ROOM"PROC_SIDEBAND"
SEC"1"
BOM_COST"PROC_SIDEBAND"
CDS_LOCATION"C8E2"
CDS_LIB"dev_discrete"
VALUE"0.1UF"
LOCATION"C8E2"
VOLTAGE"16V"
MATERIAL"X7R"
PACK_TYPE"0402V"
TOLERANCE"10%"
PART_NUMBER"A36096-030";
"B"
$PN"2"7;
"A"
$PN"1"6;
%"GND"
"1","(-1575,4825)","0","mstr_symbols","I41";
;
SIZE"1B"
HDL_POWER"GND"
CDS_LIB"mstr_symbols"
VOLTAGE"0.0V"
BODY_TYPE"PLUMBING";
"A\NAC"7;
%"CAP"
"1","(-3700,4250)","0","mstr_discrete","I42";
;
CDS_SEC"1"
CDS_LOCATION"C8D3"
SEC_TYPE"0402LF"
BOM_COST"PROC_SIDEBAND"
SEC"1"
ROOM"PROC_SIDEBAND"
CDS_LIB"mstr_discrete"
VOLTAGE"50V"
TOLERANCE"10%"
VALUE"470PF"
PART_NUMBER"A36096-049"
LOCATION"C8D3"
MATERIAL"EMPTY"
PACK_TYPE"0402LF";
"A"
$PN"1"29;
"B"
$PN"2"8;
%"GND"
"1","(-3700,3950)","0","mstr_symbols","I43";
;
HDL_POWER"GND"
BODY_TYPE"PLUMBING"
SIZE"1B"
CDS_LIB"mstr_symbols"
VOLTAGE"0.0V";
"A\NAC"8;
%"TTL1G07_A"
"1","(-1400,2525)","0","mstr_ttl","I46";
;
CDS_SEC"1"
BOM_COST"FAST_PROCHOT"
SEC_TYPE"SOP"
SEC"1"
CDS_LOCATION"U1R1"
PACK_TYPE"SOP"
ROOM"FAST_PROCHOT"
CDS_LIB"mstr_ttl"
MATERIAL"IC"
VALUE"74LVC1G07"
LOCATION"U1R1"
PART_NUMBER"C88419-001"
POWER_GROUP"VCC=P3V3_STBY;GND=GND";
"Y"
$PN"4"32;
"A"
$PN"2"33;
%"P3V3_STBY"
"1","(-1600,1950)","0","mstr_symbols","I48";
;
CDS_LIB"mstr_symbols"
SIZE"1B"
BODY_TYPE"PLUMBING"
VOLTAGE"3.3V"
HDL_POWER"P3V3_STBY";
"G\NAC"9;
%"CAP_A"
"1","(-1600,1700)","0","dev_discrete","I49";
;
BOM_COST"FAST_PROCHOT"
SEC_TYPE"0402V"
SEC"1"
CDS_LOCATION"C1R28"
CDS_SEC"1"
ROOM"FAST_PROCHOT"
CDS_LIB"dev_discrete"
MATERIAL"X7R"
VOLTAGE"16V"
PACK_TYPE"0402V"
TOLERANCE"10%"
VALUE"0.1UF"
PART_NUMBER"A36096-030"
LOCATION"C1R28";
"B"
$PN"2"10;
"A"
$PN"1"9;
%"GND"
"1","(-1600,1425)","0","mstr_symbols","I50";
;
SIZE"1B"
HDL_POWER"GND"
CDS_LIB"mstr_symbols"
BODY_TYPE"PLUMBING"
VOLTAGE"0.0V";
"A\NAC"10;
%"RES"
"1","(-650,2525)","0","mstr_discrete","I51";
;
CDS_SEC"1"
SEC_TYPE"0402"
SEC"1"
CDS_LOCATION"R1R8"
BOM_COST"PROC_SIDEBAND"
CDS_LIB"mstr_discrete"
ROOM"PROC_SIDEBAND"
WATTAGE"1/16W"
TOLERANCE"5%"
PART_NUMBER"G21497-005"
LOCATION"R1R8"
PACK_TYPE"0402"
VALUE"0.0"
MATERIAL"CHIP";
"B"
$PN"2"31;
"A"
$PN"1"32;
%"RES"
"2","(-3825,5100)","0","mstr_discrete","I52";
;
CDS_SEC"1"
BOM_COST"PROC_SIDEBAND"
SEC_TYPE"0402"
ROOM"PROC_SIDEBAND"
SEC"1"
CDS_LOCATION"R2P8"
CDS_LIB"mstr_discrete"
LOCATION"R2P8"
VALUE"560"
TOLERANCE"5%"
PART_NUMBER"G21497-062"
WATTAGE"1/16W"
MATERIAL"CHIP"
PACK_TYPE"0402";
"A"
$PN"1"11;
"B"
$PN"2"29;
%"P3V3_STBY"
"1","(-3825,5475)","0","mstr_symbols","I53";
;
CDS_LIB"mstr_symbols"
SIZE"1B"
BODY_TYPE"PLUMBING"
VOLTAGE"3.3V"
HDL_POWER"P3V3_STBY";
"G\NAC"11;
%"RES"
"2","(-3450,2075)","0","mstr_discrete","I54";
;
CDS_SEC"1"
BOM_COST"FAST_PROCHOT"
SEC_TYPE"0402"
SEC"1"
ROOM"FAST_PROCHOT"
CDS_LOCATION"R2T3"
CDS_LIB"mstr_discrete"
WATTAGE"1/16W"
VALUE"4.75K"
LOCATION"R2T3"
TOLERANCE"1%"
MATERIAL"CHIP"
PACK_TYPE"0402"
PART_NUMBER"G21796-072";
"A"
$PN"1"12;
"B"
$PN"2"38;
%"P3V3_STBY"
"1","(-3450,2350)","0","mstr_symbols","I55";
;
SIZE"1B"
VOLTAGE"3.3V"
CDS_LIB"mstr_symbols"
BODY_TYPE"PLUMBING"
HDL_POWER"P3V3_STBY";
"G\NAC"12;
%"RES"
"2","(-4150,5100)","0","mstr_discrete","I56";
;
CDS_SEC"1"
CDS_LOCATION"R2P5"
BOM_COST"PROC_SIDEBAND"
SEC_TYPE"0402"
SEC"1"
ROOM"PROC_SIDEBAND"
CDS_LIB"mstr_discrete"
LOCATION"R2P5"
VALUE"4.75K"
TOLERANCE"1%"
WATTAGE"1/16W"
MATERIAL"CHIP"
PACK_TYPE"0402"
PART_NUMBER"G21796-072";
"A"
$PN"1"11;
"B"
$PN"2"28;
%"FET_N"
"8","(-4150,4225)","0","mstr_discrete","I58";
;
CDS_SEC"1"
SEC_TYPE"SOT23LF"
BOM_COST"PROC_SIDEBAND"
SEC"1"
CDS_LOCATION"Q2P1"
ROOM"PROC_SIDEBAND"
PACK_TYPE"SOT23LF"
CDS_LIB"mstr_discrete"
VALUE"2N7002"
LOCATION"Q2P1"
MATERIAL"FET"
PART_NUMBER"C79254-001";
"GATE"
$PN"1"39;
"DRN"
$PN"3"28;
"SRC"
$PN"2"14;
%"P3V3_STBY"
"1","(-5100,3600)","0","mstr_symbols","I6";
;
CDS_LIB"mstr_symbols"
SIZE"1B"
BODY_TYPE"PLUMBING"
HDL_POWER"P3V3_STBY"
VOLTAGE"3.3V";
"G\NAC"13;
%"GND"
"1","(-4150,3900)","0","mstr_symbols","I60";
;
SIZE"1B"
HDL_POWER"GND"
BODY_TYPE"PLUMBING"
CDS_LIB"mstr_symbols"
VOLTAGE"0.0V";
"A\NAC"14;
%"RES"
"2","(-4600,4350)","0","mstr_discrete","I61";
;
CDS_SEC"1"
BOM_COST"PROC_SIDEBAND"
SEC_TYPE"0402"
ROOM"PROC_SIDEBAND"
SEC"1"
CDS_LOCATION"R2P13"
CDS_LIB"mstr_discrete"
PART_NUMBER"G21796-072"
VALUE"4.75K"
LOCATION"R2P13"
TOLERANCE"1%"
WATTAGE"1/16W"
MATERIAL"CHIP"
PACK_TYPE"0402";
"A"
$PN"1"15;
"B"
$PN"2"39;
%"P3V3_STBY"
"1","(-4600,4575)","0","mstr_symbols","I62";
;
SIZE"1B"
CDS_LIB"mstr_symbols"
BODY_TYPE"PLUMBING"
HDL_POWER"P3V3_STBY"
VOLTAGE"3.3V";
"G\NAC"15;
%"RES"
"2","(-4525,3925)","0","mstr_discrete","I63";
;
BOM_COST"PROC_SIDEBAND"
CDS_SEC"1"
$SEC"1"
ROOM"PROC_SIDEBAND"
CDS_LOCATION"R2P11"
CDS_LIB"mstr_discrete"
WATTAGE"1/16W"
VALUE"1.00K"
PART_NUMBER"G21796-026"
LOCATION"R2P11"
MATERIAL"EMPTY"
TOLERANCE"1%"
PACK_TYPE"0402";
"A"
$PN"1"39;
"B"
$PN"2"16;
%"GND"
"1","(-4525,3700)","0","mstr_symbols","I64";
;
HDL_POWER"GND"
SIZE"1B"
CDS_LIB"mstr_symbols"
BODY_TYPE"PLUMBING"
VOLTAGE"0.0V";
"A\NAC"16;
%"RES"
"2","(-2950,2775)","0","mstr_discrete","I65";
;
CDS_SEC"1"
SEC_TYPE"0402"
BOM_COST"PROC_SIDEBAND"
ROOM"PROC_SIDEBAND"
CDS_LOCATION"R9F3"
SEC"1"
CDS_LIB"mstr_discrete"
WATTAGE"1/16W"
MATERIAL"CHIP"
PACK_TYPE"0402"
VALUE"4.75K"
PART_NUMBER"G21796-072"
LOCATION"R9F3"
TOLERANCE"1%";
"A"
$PN"1"17;
"B"
$PN"2"36;
%"P3V3_STBY"
"1","(-2950,3000)","0","mstr_symbols","I66";
;
SIZE"1B"
BODY_TYPE"PLUMBING"
CDS_LIB"mstr_symbols"
VOLTAGE"3.3V"
HDL_POWER"P3V3_STBY";
"G\NAC"17;
%"FET_N"
"8","(-2950,1900)","0","mstr_discrete","I67";
;
CDS_SEC"1"
BOM_COST"PROC_SIDEBAND"
SEC_TYPE"SOT23LF"
SEC"1"
CDS_LOCATION"Q8F2"
ROOM"PROC_SIDEBAND"
PACK_TYPE"SOT23LF"
CDS_LIB"mstr_discrete"
PART_NUMBER"C79254-001"
MATERIAL"FET"
VALUE"2N7002"
LOCATION"Q8F2";
"GATE"
$PN"1"38;
"DRN"
$PN"3"36;
"SRC"
$PN"2"18;
%"GND"
"1","(-2950,1575)","0","mstr_symbols","I68";
;
CDS_LIB"mstr_symbols"
HDL_POWER"GND"
SIZE"1B"
BODY_TYPE"PLUMBING"
VOLTAGE"0.0V";
"A\NAC"18;
%"GND"
"1","(-5100,3075)","0","mstr_symbols","I7";
;
CDS_LIB"mstr_symbols"
HDL_POWER"GND"
SIZE"1B"
BODY_TYPE"PLUMBING"
VOLTAGE"0.0V";
"A\NAC"19;
%"P3V3_STBY"
"1","(-3150,5475)","0","mstr_symbols","I70";
;
VOLTAGE"3.3V"
SIZE"1B"
CDS_LIB"mstr_symbols"
BODY_TYPE"PLUMBING"
HDL_POWER"P3V3_STBY";
"G\NAC"20;
%"RES"
"2","(-3150,5100)","0","mstr_discrete","I71";
;
CDS_SEC"1"
CDS_LOCATION"R8D26"
SEC"1"
BOM_COST"FAST_PROCHOT"
SEC_TYPE"0402"
ROOM"FAST_PROCHOT"
CDS_LIB"mstr_discrete"
LOCATION"R8D26"
VALUE"4.75K"
TOLERANCE"1%"
WATTAGE"1/16W"
MATERIAL"CHIP"
PART_NUMBER"G21796-072"
PACK_TYPE"0402";
"A"
$PN"1"20;
"B"
$PN"2"27;
%"P3V3_STBY"
"1","(-2025,3075)","0","mstr_symbols","I72";
;
CDS_LIB"mstr_symbols"
SIZE"1B"
BODY_TYPE"PLUMBING"
HDL_POWER"P3V3_STBY"
VOLTAGE"3.3V";
"G\NAC"21;
%"RES"
"2","(-2025,2850)","0","mstr_discrete","I73";
;
CDS_SEC"1"
BOM_COST"FAST_PROCHOT"
SEC_TYPE"0402"
SEC"1"
ROOM"FAST_PROCHOT"
CDS_LOCATION"R1R5"
CDS_LIB"mstr_discrete"
PART_NUMBER"G21796-072"
WATTAGE"1/16W"
VALUE"4.75K"
LOCATION"R1R5"
TOLERANCE"1%"
PACK_TYPE"0402"
MATERIAL"CHIP";
"A"
$PN"1"21;
"B"
$PN"2"33;
%"RES"
"1","(-1900,4775)","0","mstr_discrete","I74";
;
CDS_SEC"1"
$SEC"1"
CDS_LIB"mstr_discrete"
CDS_LOCATION"R2P4"
PACK_TYPE"0402"
MATERIAL"CHIP"
PART_NUMBER"G21796-074"
TOLERANCE"1%"
LOCATION"R2P4"
VALUE"33.2"
WATTAGE"1/16W";
"B"
$PN"2"24;
"A"
$PN"1"26;
%"CAP_A"
"1","(-5100,3350)","0","dev_discrete","I8";
;
BOM_COST"FAST_PROCHOT"
SEC_TYPE"0402V"
ROOM"FAST_PROCHOT"
SEC"1"
CDS_SEC"1"
CDS_LIB"dev_discrete"
CDS_LOCATION"C2P1"
PART_NUMBER"A36096-030"
LOCATION"C2P1"
VALUE"0.1UF"
VOLTAGE"16V"
PACK_TYPE"0402V"
TOLERANCE"10%"
MATERIAL"X7R";
"B"
$PN"2"19;
"A"
$PN"1"13;
END.
